(kicad_pcb
	(version 20260206)
	(generator "pcbnew")
	(generator_version "10.0")
	(general
		(thickness 1.6)
		(legacy_teardrops no)
	)
	(paper "A4")
	(title_block
		(title "v1-chassis-manager — T6M_CM_d_v01_1031_1645.brd")
		(comment 1 "Open CloudServer (Microsoft) / footprints 708-715 of 2512")
	)
	(layers
		(0 "F.Cu" signal "TOP")
		(4 "In1.Cu" signal "GND1")
		(6 "In2.Cu" signal "IN1")
		(8 "In3.Cu" signal "VCC1")
		(10 "In4.Cu" signal "VCC2")
		(12 "In5.Cu" signal "GND2")
		(14 "In6.Cu" signal "IN2")
		(16 "In7.Cu" signal "IN3")
		(18 "In8.Cu" signal "GND3")
		(2 "B.Cu" signal "BOTTOM")
		(9 "F.Adhes" user "F.Adhesive")
		(11 "B.Adhes" user "B.Adhesive")
		(13 "F.Paste" user "Package Geometry/Pastemask Top")
		(15 "B.Paste" user "Package Geometry/Pastemask Bottom")
		(5 "F.SilkS" user "Ref Des/Silkscreen Top")
		(7 "B.SilkS" user "Ref Des/Silkscreen Bottom")
		(1 "F.Mask" user "Board Geometry/Soldermask Top")
		(3 "B.Mask" user "Board Geometry/Soldermask Bottom")
		(17 "Dwgs.User" user "User.Drawings")
		(19 "Cmts.User" user "User.Comments")
		(21 "Eco1.User" user "User.Eco1")
		(23 "Eco2.User" user "User.Eco2")
		(25 "Edge.Cuts" user "Board Geometry/Outline")
		(27 "Margin" user)
		(31 "F.CrtYd" user "Package Geometry/Place Bound Top")
		(29 "B.CrtYd" user "Package Geometry/Place Bound Bottom")
		(35 "F.Fab" user "Ref Des/Assembly Top")
		(33 "B.Fab" user "Ref Des/Assembly Bottom")
	)
	(footprint ""
		(layer "F.Cu")
		(at 6.83387 -161.141156 180)
		(property "Reference" "U55"
			(at 2.39903 4.611878 0)
			(unlocked yes)
			(layer "F.SilkS")
			(effects
				(font
					(size 0.7874 0.5842)
					(thickness 0.1524)
				)
				(justify left)
			)
		)
		(property "Value" ""
			(at 0 0 180)
			(layer "F.Fab")
			(effects
				(font
					(size 1.27 1.27)
				)
			)
		)
		(duplicate_pad_numbers_are_jumpers no)
		(fp_line
			(start 4.9022 2.0066)
			(end -4.9022 2.0066)
			(stroke
				(width 0.1524)
				(type default)
			)
			(layer "F.SilkS")
		)
		(fp_line
			(start 4.9022 -2.0066)
			(end 4.9022 2.0066)
			(stroke
				(width 0.1524)
				(type default)
			)
			(layer "F.SilkS")
		)
		(fp_line
			(start -4.318 0)
			(end -4.9022 -0.5842)
			(stroke
				(width 0.1524)
				(type default)
			)
			(layer "F.SilkS")
		)
		(fp_line
			(start -4.9022 2.0066)
			(end -4.9022 0.5842)
			(stroke
				(width 0.1524)
				(type default)
			)
			(layer "F.SilkS")
		)
		(fp_line
			(start -4.9022 0.5842)
			(end -4.318 0)
			(stroke
				(width 0.1524)
				(type default)
			)
			(layer "F.SilkS")
		)
		(fp_line
			(start -4.9022 -0.5842)
			(end -4.9022 -2.0066)
			(stroke
				(width 0.1524)
				(type default)
			)
			(layer "F.SilkS")
		)
		(fp_line
			(start -4.9022 -2.0066)
			(end 4.9022 -2.0066)
			(stroke
				(width 0.1524)
				(type default)
			)
			(layer "F.SilkS")
		)
		(fp_circle
			(center -4.318 1.524)
			(end -4.572 1.524)
			(stroke
				(width 0.1524)
				(type default)
			)
			(fill no)
			(layer "F.SilkS")
		)
		(fp_rect
			(start -4.9022 3.6703)
			(end 4.9022 -3.6703)
			(stroke
				(width 0)
				(type default)
			)
			(fill no)
			(layer "F.CrtYd")
		)
		(pad "1" smd rect
			(at -4.225036 2.921 180)
			(size 0.3556 1.4986)
			(layers "F.Cu" "F.Mask" "F.Paste")
			(net "N54258523")
		)
		(pad "2" smd rect
			(at -3.57505 2.921 180)
			(size 0.3556 1.4986)
			(layers "F.Cu" "F.Mask" "F.Paste")
			(net "N54258525")
		)
		(pad "3" smd rect
			(at -2.925064 2.921 180)
			(size 0.3556 1.4986)
			(layers "F.Cu" "F.Mask" "F.Paste")
			(net "N54258537")
		)
		(pad "4" smd rect
			(at -2.275078 2.921 180)
			(size 0.3556 1.4986)
			(layers "F.Cu" "F.Mask" "F.Paste")
			(net "UART_RX_P5_L")
		)
		(pad "5" smd rect
			(at -1.625092 2.921 180)
			(size 0.3556 1.4986)
			(layers "F.Cu" "F.Mask" "F.Paste")
			(net "UART_RI_P5_L_N")
		)
		(pad "6" smd rect
			(at -0.975106 2.921 180)
			(size 0.3556 1.4986)
			(layers "F.Cu" "F.Mask" "F.Paste")
			(net "UART_DSR_P5_L_N")
		)
		(pad "7" smd rect
			(at -0.32512 2.921 180)
			(size 0.3556 1.4986)
			(layers "F.Cu" "F.Mask" "F.Paste")
			(net "UART_CTS_P5_L_N")
		)
		(pad "8" smd rect
			(at 0.32512 2.921 180)
			(size 0.3556 1.4986)
			(layers "F.Cu" "F.Mask" "F.Paste")
			(net "N54258454")
		)
		(pad "9" smd rect
			(at 0.975106 2.921 180)
			(size 0.3556 1.4986)
			(layers "F.Cu" "F.Mask" "F.Paste")
			(net "UART_RTS_P5_L_N")
		)
		(pad "10" smd rect
			(at 1.625092 2.921 180)
			(size 0.3556 1.4986)
			(layers "F.Cu" "F.Mask" "F.Paste")
			(net "UART_TX_P5_L")
		)
		(pad "11" smd rect
			(at 2.275078 2.921 180)
			(size 0.3556 1.4986)
			(layers "F.Cu" "F.Mask" "F.Paste")
			(net "UART_DTR_P5_L_N")
		)
		(pad "12" smd rect
			(at 2.925064 2.921 180)
			(size 0.3556 1.4986)
			(layers "F.Cu" "F.Mask" "F.Paste")
			(net "UART_DTR_P5_N")
		)
		(pad "13" smd rect
			(at 3.57505 2.921 180)
			(size 0.3556 1.4986)
			(layers "F.Cu" "F.Mask" "F.Paste")
			(net "UART_TX_P5")
		)
		(pad "14" smd rect
			(at 4.225036 2.921 180)
			(size 0.3556 1.4986)
			(layers "F.Cu" "F.Mask" "F.Paste")
			(net "UART_RTS_P5_N")
		)
		(pad "15" smd rect
			(at 4.225036 -2.921 180)
			(size 0.3556 1.4986)
			(layers "F.Cu" "F.Mask" "F.Paste")
			(net "Net_2306")
		)
		(pad "16" smd rect
			(at 3.57505 -2.921 180)
			(size 0.3556 1.4986)
			(layers "F.Cu" "F.Mask" "F.Paste")
			(net "UART_CTS_P5_N")
		)
		(pad "17" smd rect
			(at 2.925064 -2.921 180)
			(size 0.3556 1.4986)
			(layers "F.Cu" "F.Mask" "F.Paste")
			(net "UART_DSR_P5_N")
		)
		(pad "18" smd rect
			(at 2.275078 -2.921 180)
			(size 0.3556 1.4986)
			(layers "F.Cu" "F.Mask" "F.Paste")
			(net "UART_RI_P5_LS_N")
		)
		(pad "19" smd rect
			(at 1.625092 -2.921 180)
			(size 0.3556 1.4986)
			(layers "F.Cu" "F.Mask" "F.Paste")
			(net "UART_RX_P5")
		)
		(pad "20" smd rect
			(at 0.975106 -2.921 180)
			(size 0.3556 1.4986)
			(layers "F.Cu" "F.Mask" "F.Paste")
			(net "Net_2307")
		)
		(pad "21" smd rect
			(at 0.32512 -2.921 180)
			(size 0.3556 1.4986)
			(layers "F.Cu" "F.Mask" "F.Paste")
			(net "Net_2308")
		)
		(pad "22" smd rect
			(at -0.32512 -2.921 180)
			(size 0.3556 1.4986)
			(layers "F.Cu" "F.Mask" "F.Paste")
			(net "N54258476")
		)
		(pad "23" smd rect
			(at -0.975106 -2.921 180)
			(size 0.3556 1.4986)
			(layers "F.Cu" "F.Mask" "F.Paste")
			(net "N54258474")
		)
		(pad "24" smd rect
			(at -1.625092 -2.921 180)
			(size 0.3556 1.4986)
			(layers "F.Cu" "F.Mask" "F.Paste")
			(net "N54258515")
		)
		(pad "25" smd rect
			(at -2.275078 -2.921 180)
			(size 0.3556 1.4986)
			(layers "F.Cu" "F.Mask" "F.Paste")
			(net "GND")
		)
		(pad "26" smd rect
			(at -2.925064 -2.921 180)
			(size 0.3556 1.4986)
			(layers "F.Cu" "F.Mask" "F.Paste")
			(net "P3V3_NODE1")
		)
		(pad "27" smd rect
			(at -3.57505 -2.921 180)
			(size 0.3556 1.4986)
			(layers "F.Cu" "F.Mask" "F.Paste")
			(net "N54258535")
		)
		(pad "28" smd rect
			(at -4.225036 -2.921 180)
			(size 0.3556 1.4986)
			(layers "F.Cu" "F.Mask" "F.Paste")
			(net "N54258513")
		)
	)
	(footprint ""
		(layer "F.Cu")
		(at 82.429096 -152.684734)
		(property "Reference" "PC10"
			(at 1.086104 0.562356 0)
			(unlocked yes)
			(layer "F.SilkS")
			(effects
				(font
					(size 0.7874 0.5842)
					(thickness 0.1524)
				)
				(justify left)
			)
		)
		(property "Value" ""
			(at 0 0 0)
			(layer "F.Fab")
			(effects
				(font
					(size 1.27 1.27)
				)
			)
		)
		(duplicate_pad_numbers_are_jumpers no)
		(fp_line
			(start -0.7874 -0.4064)
			(end 0.7874 -0.4064)
			(stroke
				(width 0.1524)
				(type default)
			)
			(layer "F.SilkS")
		)
		(fp_line
			(start -0.7874 0.4064)
			(end -0.7874 -0.4064)
			(stroke
				(width 0.1524)
				(type default)
			)
			(layer "F.SilkS")
		)
		(fp_line
			(start 0 0.381)
			(end 0 -0.381)
			(stroke
				(width 0.1524)
				(type default)
			)
			(layer "F.SilkS")
		)
		(fp_line
			(start 0.7874 -0.4064)
			(end 0.7874 0.4064)
			(stroke
				(width 0.1524)
				(type default)
			)
			(layer "F.SilkS")
		)
		(fp_line
			(start 0.7874 0.4064)
			(end -0.7874 0.4064)
			(stroke
				(width 0.1524)
				(type default)
			)
			(layer "F.SilkS")
		)
		(fp_poly
			(pts
				(xy -0.5334 0.254) (xy -0.635 0.254) (xy -0.635 0.2286) (xy -0.635 -0.254) (xy -0.5334 -0.254) (xy -0.5334 -0.2794)
				(xy 0.5334 -0.2794) (xy 0.5334 -0.254) (xy 0.635 -0.254) (xy 0.635 0.254) (xy 0.5334 0.254) (xy 0.5334 0.2794)
				(xy -0.508 0.2794) (xy -0.5334 0.2794)
			)
			(stroke
				(width 0)
				(type default)
			)
			(fill no)
			(layer "F.CrtYd")
		)
		(pad "1" smd rect
			(at 0.40005 0)
			(size 0.4572 0.508)
			(layers "F.Cu" "F.Mask" "F.Paste")
			(net "P5V_STB_NODE1_FB")
		)
		(pad "2" smd rect
			(at -0.40005 0)
			(size 0.4572 0.508)
			(layers "F.Cu" "F.Mask" "F.Paste")
			(net "P5V_STB_NODE1")
		)
	)
	(footprint ""
		(layer "F.Cu")
		(at 66.53276 -185.205624 -90)
		(property "Reference" "R877"
			(at -4.006088 0.786892 90)
			(unlocked yes)
			(layer "F.SilkS")
			(effects
				(font
					(size 0.7874 0.5842)
					(thickness 0.1524)
				)
				(justify left)
			)
		)
		(property "Value" ""
			(at 0 0 270)
			(layer "F.Fab")
			(effects
				(font
					(size 1.27 1.27)
				)
			)
		)
		(duplicate_pad_numbers_are_jumpers no)
		(fp_line
			(start -0.7874 0.4064)
			(end -0.7874 -0.4064)
			(stroke
				(width 0.1524)
				(type default)
			)
			(layer "F.SilkS")
		)
		(fp_line
			(start 0.7874 0.4064)
			(end -0.7874 0.4064)
			(stroke
				(width 0.1524)
				(type default)
			)
			(layer "F.SilkS")
		)
		(fp_line
			(start -0.7874 -0.4064)
			(end 0.7874 -0.4064)
			(stroke
				(width 0.1524)
				(type default)
			)
			(layer "F.SilkS")
		)
		(fp_line
			(start 0.7874 -0.4064)
			(end 0.7874 0.4064)
			(stroke
				(width 0.1524)
				(type default)
			)
			(layer "F.SilkS")
		)
		(fp_poly
			(pts
				(xy -0.508 0.2794) (xy -0.508 0.2286) (xy -0.635 0.2286) (xy -0.635 -0.254) (xy -0.5334 -0.254)
				(xy -0.5334 -0.2794) (xy 0.5334 -0.2794) (xy 0.5334 -0.254) (xy 0.635 -0.254) (xy 0.635 0.254) (xy 0.5334 0.254)
				(xy 0.5334 0.2794)
			)
			(stroke
				(width 0)
				(type default)
			)
			(fill no)
			(layer "F.CrtYd")
		)
		(pad "1" smd rect
			(at 0.40005 0 270)
			(size 0.4572 0.508)
			(layers "F.Cu" "F.Mask" "F.Paste")
			(net "T2_NODE3_EN")
		)
		(pad "2" smd rect
			(at -0.40005 0 270)
			(size 0.4572 0.508)
			(layers "F.Cu" "F.Mask" "F.Paste")
			(net "T2_NODE3_EN_R")
		)
	)
	(footprint ""
		(layer "F.Cu")
		(at 64.718692 -107.316016 90)
		(property "Reference" "R1113"
			(at -1.128014 7.713472 90)
			(unlocked yes)
			(layer "F.SilkS")
			(effects
				(font
					(size 0.7874 0.5842)
					(thickness 0.1524)
				)
				(justify left)
			)
		)
		(property "Value" ""
			(at 0 0 90)
			(layer "F.Fab")
			(effects
				(font
					(size 1.27 1.27)
				)
			)
		)
		(duplicate_pad_numbers_are_jumpers no)
		(fp_line
			(start 0.7874 -0.4064)
			(end 0.7874 0.4064)
			(stroke
				(width 0.1524)
				(type default)
			)
			(layer "F.SilkS")
		)
		(fp_line
			(start -0.7874 -0.4064)
			(end 0.7874 -0.4064)
			(stroke
				(width 0.1524)
				(type default)
			)
			(layer "F.SilkS")
		)
		(fp_line
			(start 0.7874 0.4064)
			(end -0.7874 0.4064)
			(stroke
				(width 0.1524)
				(type default)
			)
			(layer "F.SilkS")
		)
		(fp_line
			(start -0.7874 0.4064)
			(end -0.7874 -0.4064)
			(stroke
				(width 0.1524)
				(type default)
			)
			(layer "F.SilkS")
		)
		(fp_poly
			(pts
				(xy -0.508 0.2794) (xy -0.508 0.2286) (xy -0.635 0.2286) (xy -0.635 -0.254) (xy -0.5334 -0.254)
				(xy -0.5334 -0.2794) (xy 0.5334 -0.2794) (xy 0.5334 -0.254) (xy 0.635 -0.254) (xy 0.635 0.254) (xy 0.5334 0.254)
				(xy 0.5334 0.2794)
			)
			(stroke
				(width 0)
				(type default)
			)
			(fill no)
			(layer "F.CrtYd")
		)
		(pad "1" smd rect
			(at 0.40005 0 90)
			(size 0.4572 0.508)
			(layers "F.Cu" "F.Mask" "F.Paste")
			(net "FM_CPLD_NODE1_P1V8_EN_G")
		)
		(pad "2" smd rect
			(at -0.40005 0 90)
			(size 0.4572 0.508)
			(layers "F.Cu" "F.Mask" "F.Paste")
			(net "P3V3_STB_NODE1")
		)
	)
	(footprint ""
		(layer "F.Cu")
		(at 69.755004 -168.695624)
		(property "Reference" "C582"
			(at -4.408424 0.897636 0)
			(unlocked yes)
			(layer "F.SilkS")
			(effects
				(font
					(size 0.7874 0.5842)
					(thickness 0.1524)
				)
				(justify left)
			)
		)
		(property "Value" ""
			(at 0 0 0)
			(layer "F.Fab")
			(effects
				(font
					(size 1.27 1.27)
				)
			)
		)
		(duplicate_pad_numbers_are_jumpers no)
		(fp_line
			(start -0.7874 -0.4064)
			(end 0.7874 -0.4064)
			(stroke
				(width 0.1524)
				(type default)
			)
			(layer "F.SilkS")
		)
		(fp_line
			(start -0.7874 0.4064)
			(end -0.7874 -0.4064)
			(stroke
				(width 0.1524)
				(type default)
			)
			(layer "F.SilkS")
		)
		(fp_line
			(start 0 0.381)
			(end 0 -0.381)
			(stroke
				(width 0.1524)
				(type default)
			)
			(layer "F.SilkS")
		)
		(fp_line
			(start 0.7874 -0.4064)
			(end 0.7874 0.4064)
			(stroke
				(width 0.1524)
				(type default)
			)
			(layer "F.SilkS")
		)
		(fp_line
			(start 0.7874 0.4064)
			(end -0.7874 0.4064)
			(stroke
				(width 0.1524)
				(type default)
			)
			(layer "F.SilkS")
		)
		(fp_poly
			(pts
				(xy -0.5334 0.254) (xy -0.635 0.254) (xy -0.635 0.2286) (xy -0.635 -0.254) (xy -0.5334 -0.254) (xy -0.5334 -0.2794)
				(xy 0.5334 -0.2794) (xy 0.5334 -0.254) (xy 0.635 -0.254) (xy 0.635 0.254) (xy 0.5334 0.254) (xy 0.5334 0.2794)
				(xy -0.508 0.2794) (xy -0.5334 0.2794)
			)
			(stroke
				(width 0)
				(type default)
			)
			(fill no)
			(layer "F.CrtYd")
		)
		(pad "1" smd rect
			(at 0.40005 0)
			(size 0.4572 0.508)
			(layers "F.Cu" "F.Mask" "F.Paste")
			(net "P3V3_NODE1")
		)
		(pad "2" smd rect
			(at -0.40005 0)
			(size 0.4572 0.508)
			(layers "F.Cu" "F.Mask" "F.Paste")
			(net "GND")
		)
	)
	(footprint ""
		(layer "F.Cu")
		(at 90.81262 -180.626512 180)
		(property "Reference" "R811"
			(at -85.97646 -76.399644 0)
			(unlocked yes)
			(layer "F.SilkS")
			(effects
				(font
					(size 0.7874 0.5842)
					(thickness 0.1524)
				)
				(justify left)
			)
		)
		(property "Value" ""
			(at 0 0 180)
			(layer "F.Fab")
			(effects
				(font
					(size 1.27 1.27)
				)
			)
		)
		(duplicate_pad_numbers_are_jumpers no)
		(fp_line
			(start 0.7874 0.4064)
			(end -0.7874 0.4064)
			(stroke
				(width 0.1524)
				(type default)
			)
			(layer "F.SilkS")
		)
		(fp_line
			(start 0.7874 -0.4064)
			(end 0.7874 0.4064)
			(stroke
				(width 0.1524)
				(type default)
			)
			(layer "F.SilkS")
		)
		(fp_line
			(start -0.7874 0.4064)
			(end -0.7874 -0.4064)
			(stroke
				(width 0.1524)
				(type default)
			)
			(layer "F.SilkS")
		)
		(fp_line
			(start -0.7874 -0.4064)
			(end 0.7874 -0.4064)
			(stroke
				(width 0.1524)
				(type default)
			)
			(layer "F.SilkS")
		)
		(fp_poly
			(pts
				(xy -0.508 0.2794) (xy -0.508 0.2286) (xy -0.635 0.2286) (xy -0.635 -0.254) (xy -0.5334 -0.254)
				(xy -0.5334 -0.2794) (xy 0.5334 -0.2794) (xy 0.5334 -0.254) (xy 0.635 -0.254) (xy 0.635 0.254) (xy 0.5334 0.254)
				(xy 0.5334 0.2794)
			)
			(stroke
				(width 0)
				(type default)
			)
			(fill no)
			(layer "F.CrtYd")
		)
		(pad "1" smd rect
			(at 0.40005 0 180)
			(size 0.4572 0.508)
			(layers "F.Cu" "F.Mask" "F.Paste")
			(net "CPLD_UART_DTR_P4_N")
		)
		(pad "2" smd rect
			(at -0.40005 0 180)
			(size 0.4572 0.508)
			(layers "F.Cu" "F.Mask" "F.Paste")
			(net "GND")
		)
	)
	(footprint ""
		(layer "F.Cu")
		(at 89.954862 -17.60347)
		(property "Reference" "R207"
			(at -3.960622 0.11938 0)
			(unlocked yes)
			(layer "F.SilkS")
			(effects
				(font
					(size 0.7874 0.5842)
					(thickness 0.1524)
				)
				(justify left)
			)
		)
		(property "Value" ""
			(at 0 0 0)
			(layer "F.Fab")
			(effects
				(font
					(size 1.27 1.27)
				)
			)
		)
		(duplicate_pad_numbers_are_jumpers no)
		(fp_line
			(start -0.7874 -0.4064)
			(end 0.7874 -0.4064)
			(stroke
				(width 0.1524)
				(type default)
			)
			(layer "F.SilkS")
		)
		(fp_line
			(start -0.7874 0.4064)
			(end -0.7874 -0.4064)
			(stroke
				(width 0.1524)
				(type default)
			)
			(layer "F.SilkS")
		)
		(fp_line
			(start 0.7874 -0.4064)
			(end 0.7874 0.4064)
			(stroke
				(width 0.1524)
				(type default)
			)
			(layer "F.SilkS")
		)
		(fp_line
			(start 0.7874 0.4064)
			(end -0.7874 0.4064)
			(stroke
				(width 0.1524)
				(type default)
			)
			(layer "F.SilkS")
		)
		(fp_poly
			(pts
				(xy -0.508 0.2794) (xy -0.508 0.2286) (xy -0.635 0.2286) (xy -0.635 -0.254) (xy -0.5334 -0.254)
				(xy -0.5334 -0.2794) (xy 0.5334 -0.2794) (xy 0.5334 -0.254) (xy 0.635 -0.254) (xy 0.635 0.254) (xy 0.5334 0.254)
				(xy 0.5334 0.2794)
			)
			(stroke
				(width 0)
				(type default)
			)
			(fill no)
			(layer "F.CrtYd")
		)
		(pad "1" smd rect
			(at 0.40005 0)
			(size 0.4572 0.508)
			(layers "F.Cu" "F.Mask" "F.Paste")
			(net "GND")
		)
		(pad "2" smd rect
			(at -0.40005 0)
			(size 0.4572 0.508)
			(layers "F.Cu" "F.Mask" "F.Paste")
			(net "PD_NODE1_DM5")
		)
	)
	(footprint ""
		(layer "F.Cu")
		(at 183.2356 -188.4172 -90)
		(property "Reference" "R1292"
			(at -1.143 -0.17907 90)
			(unlocked yes)
			(layer "F.SilkS")
			(effects
				(font
					(size 0.7874 0.5842)
					(thickness 0.1524)
				)
				(justify left)
			)
		)
		(property "Value" ""
			(at 0 0 270)
			(layer "F.Fab")
			(effects
				(font
					(size 1.27 1.27)
				)
			)
		)
		(duplicate_pad_numbers_are_jumpers no)
		(fp_line
			(start -0.7874 0.4064)
			(end -0.7874 -0.4064)
			(stroke
				(width 0.1524)
				(type default)
			)
			(layer "F.SilkS")
		)
		(fp_line
			(start 0.7874 0.4064)
			(end -0.7874 0.4064)
			(stroke
				(width 0.1524)
				(type default)
			)
			(layer "F.SilkS")
		)
		(fp_line
			(start -0.7874 -0.4064)
			(end 0.7874 -0.4064)
			(stroke
				(width 0.1524)
				(type default)
			)
			(layer "F.SilkS")
		)
		(fp_line
			(start 0.7874 -0.4064)
			(end 0.7874 0.4064)
			(stroke
				(width 0.1524)
				(type default)
			)
			(layer "F.SilkS")
		)
		(fp_poly
			(pts
				(xy -0.508 0.2794) (xy -0.508 0.2286) (xy -0.635 0.2286) (xy -0.635 -0.254) (xy -0.5334 -0.254)
				(xy -0.5334 -0.2794) (xy 0.5334 -0.2794) (xy 0.5334 -0.254) (xy 0.635 -0.254) (xy 0.635 0.254) (xy 0.5334 0.254)
				(xy 0.5334 0.2794)
			)
			(stroke
				(width 0)
				(type default)
			)
			(fill no)
			(layer "F.CrtYd")
		)
		(pad "1" smd rect
			(at 0.40005 0 270)
			(size 0.4572 0.508)
			(layers "F.Cu" "F.Mask" "F.Paste")
			(net "POWER_SW1_PWR_CTR_12V")
		)
		(pad "2" smd rect
			(at -0.40005 0 270)
			(size 0.4572 0.508)
			(layers "F.Cu" "F.Mask" "F.Paste")
			(net "POWER_SW1_PWR_CTR_12V_R")
		)
	)
)
